(kicad_pcb
	(version 20260206)
	(generator "pcbnew")
	(generator_version "10.0")
	(general
		(thickness 1.6)
		(legacy_teardrops no)
	)
	(paper "A4")
	(title_block
		(title "04192023_DAF0TMB3IC0_F0TG_MB_C_brd_V02_OCP.brd")
		(comment 1 "Grand Teton / footprints 1217-1224 of 8354")
	)
	(layers
		(0 "F.Cu" signal "TOP")
		(4 "In1.Cu" signal "GND")
		(6 "In2.Cu" signal "IN1")
		(8 "In3.Cu" signal "GND1")
		(10 "In4.Cu" signal "IN2")
		(12 "In5.Cu" signal "GND2")
		(14 "In6.Cu" signal "IN3")
		(16 "In7.Cu" signal "GND3")
		(18 "In8.Cu" signal "VCC")
		(20 "In9.Cu" signal "VCC1")
		(22 "In10.Cu" signal "GND4")
		(24 "In11.Cu" signal "IN4")
		(26 "In12.Cu" signal "GND5")
		(28 "In13.Cu" signal "IN5")
		(30 "In14.Cu" signal "GND6")
		(32 "In15.Cu" signal "IN6")
		(34 "In16.Cu" signal "GND7")
		(2 "B.Cu" signal "BOTTOM")
		(9 "F.Adhes" user "F.Adhesive")
		(11 "B.Adhes" user "B.Adhesive")
		(13 "F.Paste" user "Package Geometry/Pastemask Top")
		(15 "B.Paste" user "Package Geometry/Pastemask Bottom")
		(5 "F.SilkS" user "Ref Des/Silkscreen Top")
		(7 "B.SilkS" user "Ref Des/Silkscreen Bottom")
		(1 "F.Mask" user "Board Geometry/Soldermask Top")
		(3 "B.Mask" user "Board Geometry/Soldermask Bottom")
		(17 "Dwgs.User" user "User.Drawings")
		(19 "Cmts.User" user "User.Comments")
		(21 "Eco1.User" user "User.Eco1")
		(23 "Eco2.User" user "User.Eco2")
		(25 "Edge.Cuts" user "Board Geometry/Outline")
		(27 "Margin" user)
		(31 "F.CrtYd" user "Package Geometry/Place Bound Top")
		(29 "B.CrtYd" user "Package Geometry/Place Bound Bottom")
		(35 "F.Fab" user "Ref Des/Assembly Top")
		(33 "B.Fab" user "Ref Des/Assembly Bottom")
	)
	(footprint ""
		(layer "F.Cu")
		(at 330.196444 -138.893042 90)
		(property "Reference" "PR471"
			(at 0 0 90)
			(layer "F.SilkS")
			(hide yes)
			(effects
				(font
					(size 1.27 1.27)
				)
			)
		)
		(property "Value" ""
			(at 0 0 90)
			(layer "F.Fab")
			(effects
				(font
					(size 1.27 1.27)
				)
			)
		)
		(duplicate_pad_numbers_are_jumpers no)
		(fp_line
			(start 0.7874 -0.4064)
			(end 0.7874 0.4064)
			(stroke
				(width 0.1524)
				(type default)
			)
			(layer "F.SilkS")
		)
		(fp_line
			(start -0.7874 -0.4064)
			(end 0.7874 -0.4064)
			(stroke
				(width 0.1524)
				(type default)
			)
			(layer "F.SilkS")
		)
		(fp_line
			(start 0.7874 0.4064)
			(end -0.7874 0.4064)
			(stroke
				(width 0.1524)
				(type default)
			)
			(layer "F.SilkS")
		)
		(fp_line
			(start -0.7874 0.4064)
			(end -0.7874 -0.4064)
			(stroke
				(width 0.1524)
				(type default)
			)
			(layer "F.SilkS")
		)
		(fp_line
			(start -0.12065 -0.305054)
			(end -0.12065 -0.2794)
			(stroke
				(width 0.1)
				(type default)
			)
			(layer "F.Fab")
		)
		(fp_line
			(start -0.67945 -0.305054)
			(end -0.12065 -0.305054)
			(stroke
				(width 0.1)
				(type default)
			)
			(layer "F.Fab")
		)
		(fp_line
			(start 0.67945 -0.3048)
			(end 0.67945 0.3048)
			(stroke
				(width 0.1)
				(type default)
			)
			(layer "F.Fab")
		)
		(fp_line
			(start 0.12065 -0.3048)
			(end 0.67945 -0.3048)
			(stroke
				(width 0.1)
				(type default)
			)
			(layer "F.Fab")
		)
		(fp_line
			(start 0.12065 -0.2794)
			(end 0.12065 -0.3048)
			(stroke
				(width 0.1)
				(type default)
			)
			(layer "F.Fab")
		)
		(fp_line
			(start -0.12065 -0.2794)
			(end 0.12065 -0.2794)
			(stroke
				(width 0.1)
				(type default)
			)
			(layer "F.Fab")
		)
		(fp_line
			(start 0.120396 0.2794)
			(end -0.12065 0.2794)
			(stroke
				(width 0.1)
				(type default)
			)
			(layer "F.Fab")
		)
		(fp_line
			(start -0.12065 0.2794)
			(end -0.12065 0.3048)
			(stroke
				(width 0.1)
				(type default)
			)
			(layer "F.Fab")
		)
		(fp_line
			(start 0.67945 0.3048)
			(end 0.120396 0.3048)
			(stroke
				(width 0.1)
				(type default)
			)
			(layer "F.Fab")
		)
		(fp_line
			(start 0.120396 0.3048)
			(end 0.120396 0.2794)
			(stroke
				(width 0.1)
				(type default)
			)
			(layer "F.Fab")
		)
		(fp_line
			(start -0.12065 0.3048)
			(end -0.67945 0.3048)
			(stroke
				(width 0.1)
				(type default)
			)
			(layer "F.Fab")
		)
		(fp_line
			(start -0.67945 0.3048)
			(end -0.67945 -0.305054)
			(stroke
				(width 0.1)
				(type default)
			)
			(layer "F.Fab")
		)
		(pad "1" smd circle
			(at -0.40005 0 90)
			(size 0 0)
			(layers "F.Cu" "F.Mask" "F.Paste")
			(net "PVDD18_S5_P0_FB")
		)
		(pad "2" smd circle
			(at 0.40005 0 90)
			(size 0 0)
			(layers "F.Cu" "F.Mask" "F.Paste")
			(net "PVDD18_S5_P0_FB_RC")
		)
	)
	(footprint ""
		(layer "F.Cu")
		(at 257.951478 -108.179108 180)
		(property "Reference" "R3190"
			(at 0 0 180)
			(layer "F.SilkS")
			(hide yes)
			(effects
				(font
					(size 1.27 1.27)
				)
			)
		)
		(property "Value" ""
			(at 0 0 180)
			(layer "F.Fab")
			(effects
				(font
					(size 1.27 1.27)
				)
			)
		)
		(duplicate_pad_numbers_are_jumpers no)
		(fp_line
			(start 0.7874 0.4064)
			(end -0.7874 0.4064)
			(stroke
				(width 0.1524)
				(type default)
			)
			(layer "F.SilkS")
		)
		(fp_line
			(start 0.7874 -0.4064)
			(end 0.7874 0.4064)
			(stroke
				(width 0.1524)
				(type default)
			)
			(layer "F.SilkS")
		)
		(fp_line
			(start -0.7874 0.4064)
			(end -0.7874 -0.4064)
			(stroke
				(width 0.1524)
				(type default)
			)
			(layer "F.SilkS")
		)
		(fp_line
			(start -0.7874 -0.4064)
			(end 0.7874 -0.4064)
			(stroke
				(width 0.1524)
				(type default)
			)
			(layer "F.SilkS")
		)
		(fp_line
			(start 0.67945 0.3048)
			(end 0.120396 0.3048)
			(stroke
				(width 0.1)
				(type default)
			)
			(layer "F.Fab")
		)
		(fp_line
			(start 0.67945 -0.3048)
			(end 0.67945 0.3048)
			(stroke
				(width 0.1)
				(type default)
			)
			(layer "F.Fab")
		)
		(fp_line
			(start 0.12065 -0.2794)
			(end 0.12065 -0.3048)
			(stroke
				(width 0.1)
				(type default)
			)
			(layer "F.Fab")
		)
		(fp_line
			(start 0.12065 -0.3048)
			(end 0.67945 -0.3048)
			(stroke
				(width 0.1)
				(type default)
			)
			(layer "F.Fab")
		)
		(fp_line
			(start 0.120396 0.3048)
			(end 0.120396 0.2794)
			(stroke
				(width 0.1)
				(type default)
			)
			(layer "F.Fab")
		)
		(fp_line
			(start 0.120396 0.2794)
			(end -0.12065 0.2794)
			(stroke
				(width 0.1)
				(type default)
			)
			(layer "F.Fab")
		)
		(fp_line
			(start -0.12065 0.3048)
			(end -0.67945 0.3048)
			(stroke
				(width 0.1)
				(type default)
			)
			(layer "F.Fab")
		)
		(fp_line
			(start -0.12065 0.2794)
			(end -0.12065 0.3048)
			(stroke
				(width 0.1)
				(type default)
			)
			(layer "F.Fab")
		)
		(fp_line
			(start -0.12065 -0.2794)
			(end 0.12065 -0.2794)
			(stroke
				(width 0.1)
				(type default)
			)
			(layer "F.Fab")
		)
		(fp_line
			(start -0.12065 -0.305054)
			(end -0.12065 -0.2794)
			(stroke
				(width 0.1)
				(type default)
			)
			(layer "F.Fab")
		)
		(fp_line
			(start -0.67945 0.3048)
			(end -0.67945 -0.305054)
			(stroke
				(width 0.1)
				(type default)
			)
			(layer "F.Fab")
		)
		(fp_line
			(start -0.67945 -0.305054)
			(end -0.12065 -0.305054)
			(stroke
				(width 0.1)
				(type default)
			)
			(layer "F.Fab")
		)
		(pad "1" smd circle
			(at -0.40005 0 180)
			(size 0 0)
			(layers "F.Cu" "F.Mask" "F.Paste")
			(net "P3V3_AUX")
		)
		(pad "2" smd circle
			(at 0.40005 0 180)
			(size 0 0)
			(layers "F.Cu" "F.Mask" "F.Paste")
			(net "OCP_V3_2_PWRBRK_BUFF_N")
		)
	)
	(footprint ""
		(layer "F.Cu")
		(at 161.30524 -36.739322 90)
		(property "Reference" "C1663"
			(at 0 0 90)
			(layer "F.SilkS")
			(hide yes)
			(effects
				(font
					(size 1.27 1.27)
				)
			)
		)
		(property "Value" ""
			(at 0 0 90)
			(layer "F.Fab")
			(effects
				(font
					(size 1.27 1.27)
				)
			)
		)
		(duplicate_pad_numbers_are_jumpers no)
		(fp_line
			(start 0.7874 -0.4064)
			(end 0.7874 0.4064)
			(stroke
				(width 0.1524)
				(type default)
			)
			(layer "F.SilkS")
		)
		(fp_line
			(start -0.7874 -0.4064)
			(end 0.7874 -0.4064)
			(stroke
				(width 0.1524)
				(type default)
			)
			(layer "F.SilkS")
		)
		(fp_line
			(start 0.7874 0.4064)
			(end -0.7874 0.4064)
			(stroke
				(width 0.1524)
				(type default)
			)
			(layer "F.SilkS")
		)
		(fp_line
			(start -0.7874 0.4064)
			(end -0.7874 -0.4064)
			(stroke
				(width 0.1524)
				(type default)
			)
			(layer "F.SilkS")
		)
		(fp_line
			(start -0.12065 -0.305054)
			(end -0.12065 -0.2794)
			(stroke
				(width 0.1)
				(type default)
			)
			(layer "F.Fab")
		)
		(fp_line
			(start -0.67945 -0.305054)
			(end -0.12065 -0.305054)
			(stroke
				(width 0.1)
				(type default)
			)
			(layer "F.Fab")
		)
		(fp_line
			(start 0.67945 -0.3048)
			(end 0.67945 0.3048)
			(stroke
				(width 0.1)
				(type default)
			)
			(layer "F.Fab")
		)
		(fp_line
			(start 0.12065 -0.3048)
			(end 0.67945 -0.3048)
			(stroke
				(width 0.1)
				(type default)
			)
			(layer "F.Fab")
		)
		(fp_line
			(start 0.12065 -0.2794)
			(end 0.12065 -0.3048)
			(stroke
				(width 0.1)
				(type default)
			)
			(layer "F.Fab")
		)
		(fp_line
			(start -0.12065 -0.2794)
			(end 0.12065 -0.2794)
			(stroke
				(width 0.1)
				(type default)
			)
			(layer "F.Fab")
		)
		(fp_line
			(start 0.120396 0.2794)
			(end -0.12065 0.2794)
			(stroke
				(width 0.1)
				(type default)
			)
			(layer "F.Fab")
		)
		(fp_line
			(start -0.12065 0.2794)
			(end -0.12065 0.3048)
			(stroke
				(width 0.1)
				(type default)
			)
			(layer "F.Fab")
		)
		(fp_line
			(start 0.67945 0.3048)
			(end 0.120396 0.3048)
			(stroke
				(width 0.1)
				(type default)
			)
			(layer "F.Fab")
		)
		(fp_line
			(start 0.120396 0.3048)
			(end 0.120396 0.2794)
			(stroke
				(width 0.1)
				(type default)
			)
			(layer "F.Fab")
		)
		(fp_line
			(start -0.12065 0.3048)
			(end -0.67945 0.3048)
			(stroke
				(width 0.1)
				(type default)
			)
			(layer "F.Fab")
		)
		(fp_line
			(start -0.67945 0.3048)
			(end -0.67945 -0.305054)
			(stroke
				(width 0.1)
				(type default)
			)
			(layer "F.Fab")
		)
		(pad "1" smd circle
			(at -0.40005 0 90)
			(size 0 0)
			(layers "F.Cu" "F.Mask" "F.Paste")
			(net "P3V3_AUX")
		)
		(pad "2" smd circle
			(at 0.40005 0 90)
			(size 0 0)
			(layers "F.Cu" "F.Mask" "F.Paste")
			(net "GND")
		)
	)
	(footprint ""
		(layer "F.Cu")
		(at 51.698906 19.444716 -90)
		(property "Reference" "JP4003_12"
			(at 0 0 270)
			(layer "F.SilkS")
			(hide yes)
			(effects
				(font
					(size 1.27 1.27)
				)
			)
		)
		(property "Value" ""
			(at 0 0 270)
			(layer "F.Fab")
			(effects
				(font
					(size 1.27 1.27)
				)
			)
		)
		(duplicate_pad_numbers_are_jumpers no)
		(pad "1" smd circle
			(at 0 0 270)
			(size 0.762 0.762)
			(layers "F.Cu" "F.Mask" "F.Paste")
			(net "Net_10793")
		)
	)
	(footprint ""
		(layer "F.Cu")
		(at 311.937908 -117.570504)
		(property "Reference" "U64"
			(at -1.32842 -3.188208 0)
			(unlocked yes)
			(layer "F.SilkS")
			(effects
				(font
					(size 0.7874 0.5842)
					(thickness 0.1524)
				)
				(justify left)
			)
		)
		(property "Value" ""
			(at 0 0 0)
			(layer "F.Fab")
			(effects
				(font
					(size 1.27 1.27)
				)
			)
		)
		(duplicate_pad_numbers_are_jumpers no)
		(fp_line
			(start -1.8288 -2.500122)
			(end -1.8288 2.500122)
			(stroke
				(width 0.1524)
				(type default)
			)
			(layer "F.SilkS")
		)
		(fp_line
			(start -1.8288 2.500122)
			(end 1.8288 2.500122)
			(stroke
				(width 0.1524)
				(type default)
			)
			(layer "F.SilkS")
		)
		(fp_line
			(start -1.077722 -2.500122)
			(end -1.8288 -2.500122)
			(stroke
				(width 0.1524)
				(type default)
			)
			(layer "F.SilkS")
		)
		(fp_line
			(start 0 -1.4224)
			(end -1.077722 -2.500122)
			(stroke
				(width 0.1524)
				(type default)
			)
			(layer "F.SilkS")
		)
		(fp_line
			(start 1.077722 -2.500122)
			(end 0 -1.4224)
			(stroke
				(width 0.1524)
				(type default)
			)
			(layer "F.SilkS")
		)
		(fp_line
			(start 1.8288 -2.500122)
			(end 1.077722 -2.500122)
			(stroke
				(width 0.1524)
				(type default)
			)
			(layer "F.SilkS")
		)
		(fp_line
			(start 1.8288 2.500122)
			(end 1.8288 -2.500122)
			(stroke
				(width 0.1524)
				(type default)
			)
			(layer "F.SilkS")
		)
		(fp_poly
			(pts
				(xy -2.792984 -3.610102) (xy -3.300984 -4.626102) (xy -2.284984 -4.626102)
			)
			(stroke
				(width 0)
				(type default)
			)
			(fill yes)
			(layer "F.SilkS")
		)
		(fp_line
			(start -1.999996 -2.500122)
			(end -1.999996 2.500122)
			(stroke
				(width 0.1)
				(type default)
			)
			(layer "F.Fab")
		)
		(fp_line
			(start -1.999996 2.500122)
			(end 1.999996 2.500122)
			(stroke
				(width 0.1)
				(type default)
			)
			(layer "F.Fab")
		)
		(fp_line
			(start 1.999996 -2.500122)
			(end -1.999996 -2.500122)
			(stroke
				(width 0.1)
				(type default)
			)
			(layer "F.Fab")
		)
		(fp_line
			(start 1.999996 2.500122)
			(end 1.999996 -2.500122)
			(stroke
				(width 0.1)
				(type default)
			)
			(layer "F.Fab")
		)
		(fp_poly
			(pts
				(xy -4.5085 -2.413) (xy -4.5085 -1.397) (xy -3.4925 -1.905)
			)
			(stroke
				(width 0)
				(type default)
			)
			(fill yes)
			(layer "F.Fab")
		)
		(pad "1" smd rect
			(at -2.599944 -1.905 270)
			(size 0.889 1.27)
			(layers "F.Cu" "F.Mask" "F.Paste")
			(net "MB_FRU_ADDR0")
		)
		(pad "2" smd rect
			(at -2.599944 -0.635 270)
			(size 0.889 1.27)
			(layers "F.Cu" "F.Mask" "F.Paste")
			(net "MB_FRU_ADDR1")
		)
		(pad "3" smd rect
			(at -2.599944 0.635 270)
			(size 0.889 1.27)
			(layers "F.Cu" "F.Mask" "F.Paste")
			(net "MB_FRU_ADDR2")
		)
		(pad "4" smd rect
			(at -2.599944 1.905 270)
			(size 0.889 1.27)
			(layers "F.Cu" "F.Mask" "F.Paste")
			(net "GND")
		)
		(pad "5" smd rect
			(at 2.599944 1.905 270)
			(size 0.889 1.27)
			(layers "F.Cu" "F.Mask" "F.Paste")
			(net "SMB_FRU_3V3AUX_R1_SDA")
		)
		(pad "6" smd rect
			(at 2.599944 0.635 270)
			(size 0.889 1.27)
			(layers "F.Cu" "F.Mask" "F.Paste")
			(net "SMB_FRU_3V3AUX_R1_SCL")
		)
		(pad "7" smd rect
			(at 2.599944 -0.635 270)
			(size 0.889 1.27)
			(layers "F.Cu" "F.Mask" "F.Paste")
			(net "PD_MB_FRU_WP")
		)
		(pad "8" smd rect
			(at 2.599944 -1.905 270)
			(size 0.889 1.27)
			(layers "F.Cu" "F.Mask" "F.Paste")
			(net "P3V3_AUX")
		)
	)
	(footprint ""
		(layer "F.Cu")
		(at 331.055472 -395.333474)
		(property "Reference" "R612"
			(at 0 0 0)
			(layer "F.SilkS")
			(hide yes)
			(effects
				(font
					(size 1.27 1.27)
				)
			)
		)
		(property "Value" ""
			(at 0 0 0)
			(layer "F.Fab")
			(effects
				(font
					(size 1.27 1.27)
				)
			)
		)
		(duplicate_pad_numbers_are_jumpers no)
		(fp_line
			(start -0.32512 -0.175006)
			(end 0.32512 -0.175006)
			(stroke
				(width 0.1)
				(type default)
			)
			(layer "F.Fab")
		)
		(fp_line
			(start -0.32512 0.175006)
			(end -0.32512 -0.175006)
			(stroke
				(width 0.1)
				(type default)
			)
			(layer "F.Fab")
		)
		(fp_line
			(start 0.32512 -0.175006)
			(end 0.32512 0.175006)
			(stroke
				(width 0.1)
				(type default)
			)
			(layer "F.Fab")
		)
		(fp_line
			(start 0.32512 0.175006)
			(end -0.32512 0.175006)
			(stroke
				(width 0.1)
				(type default)
			)
			(layer "F.Fab")
		)
		(pad "1" smd rect
			(at -0.2667 0)
			(size 0.3048 0.381)
			(layers "F.Cu" "F.Mask" "F.Paste")
			(net "CLK_100M_RETIMER_CPU0_P1_R_DN")
		)
		(pad "2" smd rect
			(at 0.2667 0 180)
			(size 0.3048 0.381)
			(layers "F.Cu" "F.Mask" "F.Paste")
			(net "CLK_100M_RETIMER_CPU0_P1_DN")
		)
	)
	(footprint ""
		(layer "F.Cu")
		(at 282.397962 -351.927922)
		(property "Reference" "PR106"
			(at 0 0 0)
			(layer "F.SilkS")
			(hide yes)
			(effects
				(font
					(size 1.27 1.27)
				)
			)
		)
		(property "Value" ""
			(at 0 0 0)
			(layer "F.Fab")
			(effects
				(font
					(size 1.27 1.27)
				)
			)
		)
		(duplicate_pad_numbers_are_jumpers no)
		(fp_line
			(start -0.7874 -0.4064)
			(end 0.7874 -0.4064)
			(stroke
				(width 0.1524)
				(type default)
			)
			(layer "F.SilkS")
		)
		(fp_line
			(start -0.7874 0.4064)
			(end -0.7874 -0.4064)
			(stroke
				(width 0.1524)
				(type default)
			)
			(layer "F.SilkS")
		)
		(fp_line
			(start 0.7874 -0.4064)
			(end 0.7874 0.4064)
			(stroke
				(width 0.1524)
				(type default)
			)
			(layer "F.SilkS")
		)
		(fp_line
			(start 0.7874 0.4064)
			(end -0.7874 0.4064)
			(stroke
				(width 0.1524)
				(type default)
			)
			(layer "F.SilkS")
		)
		(fp_line
			(start -0.67945 -0.305054)
			(end -0.12065 -0.305054)
			(stroke
				(width 0.1)
				(type default)
			)
			(layer "F.Fab")
		)
		(fp_line
			(start -0.67945 0.3048)
			(end -0.67945 -0.305054)
			(stroke
				(width 0.1)
				(type default)
			)
			(layer "F.Fab")
		)
		(fp_line
			(start -0.12065 -0.305054)
			(end -0.12065 -0.2794)
			(stroke
				(width 0.1)
				(type default)
			)
			(layer "F.Fab")
		)
		(fp_line
			(start -0.12065 -0.2794)
			(end 0.12065 -0.2794)
			(stroke
				(width 0.1)
				(type default)
			)
			(layer "F.Fab")
		)
		(fp_line
			(start -0.12065 0.2794)
			(end -0.12065 0.3048)
			(stroke
				(width 0.1)
				(type default)
			)
			(layer "F.Fab")
		)
		(fp_line
			(start -0.12065 0.3048)
			(end -0.67945 0.3048)
			(stroke
				(width 0.1)
				(type default)
			)
			(layer "F.Fab")
		)
		(fp_line
			(start 0.120396 0.2794)
			(end -0.12065 0.2794)
			(stroke
				(width 0.1)
				(type default)
			)
			(layer "F.Fab")
		)
		(fp_line
			(start 0.120396 0.3048)
			(end 0.120396 0.2794)
			(stroke
				(width 0.1)
				(type default)
			)
			(layer "F.Fab")
		)
		(fp_line
			(start 0.12065 -0.3048)
			(end 0.67945 -0.3048)
			(stroke
				(width 0.1)
				(type default)
			)
			(layer "F.Fab")
		)
		(fp_line
			(start 0.12065 -0.2794)
			(end 0.12065 -0.3048)
			(stroke
				(width 0.1)
				(type default)
			)
			(layer "F.Fab")
		)
		(fp_line
			(start 0.67945 -0.3048)
			(end 0.67945 0.3048)
			(stroke
				(width 0.1)
				(type default)
			)
			(layer "F.Fab")
		)
		(fp_line
			(start 0.67945 0.3048)
			(end 0.120396 0.3048)
			(stroke
				(width 0.1)
				(type default)
			)
			(layer "F.Fab")
		)
		(pad "1" smd circle
			(at -0.40005 0)
			(size 0 0)
			(layers "F.Cu" "F.Mask" "F.Paste")
			(net "PVDDIO_P0_LSET3")
		)
		(pad "2" smd circle
			(at 0.40005 0)
			(size 0 0)
			(layers "F.Cu" "F.Mask" "F.Paste")
			(net "GND")
		)
	)
	(footprint ""
		(layer "F.Cu")
		(at 45.932344 -420.513764)
		(property "Reference" "R1464"
			(at 0 0 0)
			(layer "F.SilkS")
			(hide yes)
			(effects
				(font
					(size 1.27 1.27)
				)
			)
		)
		(property "Value" ""
			(at 0 0 0)
			(layer "F.Fab")
			(effects
				(font
					(size 1.27 1.27)
				)
			)
		)
		(duplicate_pad_numbers_are_jumpers no)
		(fp_line
			(start -0.32512 -0.175006)
			(end 0.32512 -0.175006)
			(stroke
				(width 0.1)
				(type default)
			)
			(layer "F.Fab")
		)
		(fp_line
			(start -0.32512 0.175006)
			(end -0.32512 -0.175006)
			(stroke
				(width 0.1)
				(type default)
			)
			(layer "F.Fab")
		)
		(fp_line
			(start 0.32512 -0.175006)
			(end 0.32512 0.175006)
			(stroke
				(width 0.1)
				(type default)
			)
			(layer "F.Fab")
		)
		(fp_line
			(start 0.32512 0.175006)
			(end -0.32512 0.175006)
			(stroke
				(width 0.1)
				(type default)
			)
			(layer "F.Fab")
		)
		(pad "1" smd rect
			(at -0.2667 0)
			(size 0.3048 0.381)
			(layers "F.Cu" "F.Mask" "F.Paste")
			(net "P1V8_CPU1_RT_1D")
		)
		(pad "2" smd rect
			(at 0.2667 0 180)
			(size 0.3048 0.381)
			(layers "F.Cu" "F.Mask" "F.Paste")
			(net "JTAG_TDI_RT_CPU1_P0")
		)
	)
)
